# BASEBOARD_FAB2 (Tioga Pass) — schematic netlist excerpt (pin names and nets, part order shuffled) for the footprints in the layout excerpt that follows; sources: Cadence DE-HDL packaged netlist, KiCad conversion of Wiwynn_Tioga_Pass_MB.brd

J8F1  SKT-MINI67P-41-GP  pkg SOCKET-G4  page 185
  \1\  = GND
  \2\  = P3V3
  \3\  = GND
  \4\  = P3V3
  \5\  = P3E_PCH_M2_RX_DN<3>
  \6\  = NC_M2<0>
  \7\  = P3E_PCH_M2_RX_DP<3>
  \8\  = NC_M2<1>
  \9\  = GND
  \10\  = TP_LED_M2_ACT_N
  \11\  = P3E_PCH_M2_TX_C_DN<3>
  \12\  = P3V3
  \13\  = P3E_PCH_M2_TX_C_DP<3>
  \14\  = P3V3
  \15\  = GND
  \16\  = P3V3
  \17\  = P3E_PCH_M2_RX_DN<2>
  \18\  = P3V3
  \19\  = P3E_PCH_M2_RX_DP<2>
  \20\  = NC
  \21\  = GND
  \22\  = NC
  \23\  = P3E_PCH_M2_TX_C_DN<2>
  \24\  = NC
  \25\  = P3E_PCH_M2_TX_C_DP<2>
  \26\  = NC
  \27\  = GND
  \28\  = NC
  \29\  = P3E_PCH_M2_RX_DN<1>
  \30\  = NC
  \31\  = P3E_PCH_M2_RX_DP<1>
  \32\  = NC
  \33\  = GND
  \34\  = NC
  \35\  = P3E_PCH_M2_TX_C_DN<1>
  \36\  = NC
  \37\  = P3E_PCH_M2_TX_C_DP<1>
  \38\  = TP_M2_DEVSLP
  \39\  = GND
  \40\  = SMB_M2_SCL
  \41\  = P3E_PCH_M2_SATA6G_RX_R_DP
  \42\  = SMB_M2_SDA
  \43\  = P3E_PCH_M2_SATA6G_RX_R_DN
  \44\  = SMB_M2_ALT_N
  \45\  = GND
  \46\  = NC
  \47\  = P3E_PCH_M2_SATA6G_TX_R_DN
  \48\  = NC
  \49\  = P3E_PCH_M2_SATA6G_TX_R_DP
  \50\  = RST_PCIE_M2_DEV_IC_N
  \51\  = GND
  \52\  = PU_M2_CLK_REQ_N
  \53\  = CLK_100M_M2_DN
  \54\  = FM_PE_M2_WAKE_N
  \55\  = CLK_100M_M2_DP
  \56\  = NC
  \57\  = GND
  \58\  = NC
  \67\  = NC
  \68\  = TP_M2_32M_SUSCLK
  \69\  = FM_M2_SSD_PEDET
  \70\  = P3V3
  \71\  = GND
  \72\  = P3V3
  \73\  = GND
  \74\  = P3V3
  \75\  = GND
  \76\  = GND
  \77\  = GND
  NP1  = NC
  NP2  = NC

(kicad_pcb
	(version 20260206)
	(generator "pcbnew")
	(generator_version "10.0")
	(general
		(thickness 1.6)
		(legacy_teardrops no)
	)
	(paper "A4")
	(title_block
		(title "Wiwynn_Tioga_Pass_MB.brd")
		(comment 1 "Tioga Pass / footprint 894 of 4770 (J8F1), pads 1-46 of 71")
	)
	(layers
		(0 "F.Cu" signal "TOP")
		(4 "In1.Cu" signal "L2GND")
		(6 "In2.Cu" signal "L3")
		(8 "In3.Cu" signal "L4GND")
		(10 "In4.Cu" signal "L5")
		(12 "In5.Cu" signal "L6GND")
		(14 "In6.Cu" signal "L7VCC")
		(16 "In7.Cu" signal "L8VCC")
		(18 "In8.Cu" signal "L9GND")
		(20 "In9.Cu" signal "L10")
		(22 "In10.Cu" signal "L11GND")
		(24 "In11.Cu" signal "L12")
		(26 "In12.Cu" signal "L13GND")
		(2 "B.Cu" signal "BOTTOM")
		(9 "F.Adhes" user "F.Adhesive")
		(11 "B.Adhes" user "B.Adhesive")
		(13 "F.Paste" user "Package Geometry/Pastemask Top")
		(15 "B.Paste" user "Package Geometry/Pastemask Bottom")
		(5 "F.SilkS" user "Ref Des/Silkscreen Top")
		(7 "B.SilkS" user "Ref Des/Silkscreen Bottom")
		(1 "F.Mask" user "Board Geometry/Soldermask Top")
		(3 "B.Mask" user "Board Geometry/Soldermask Bottom")
		(17 "Dwgs.User" user "User.Drawings")
		(19 "Cmts.User" user "User.Comments")
		(21 "Eco1.User" user "User.Eco1")
		(23 "Eco2.User" user "User.Eco2")
		(25 "Edge.Cuts" user "Board Geometry/Outline")
		(27 "Margin" user)
		(31 "F.CrtYd" user "Package Geometry/Place Bound Top")
		(29 "B.CrtYd" user "Package Geometry/Place Bound Bottom")
		(35 "F.Fab" user "Ref Des/Assembly Top")
		(33 "B.Fab" user "Ref Des/Assembly Bottom")
	)
	(footprint ""
		(layer "F.Cu")
		(at 388.072376 -30.520894 90)
		(property "Reference" "J8F1"
			(at 0 0 90)
			(layer "F.SilkS")
			(hide yes)
			(effects
				(font
					(size 1.27 1.27)
				)
			)
		)
		(property "Value" "*"
			(at 12.319 -1.3335 90)
			(unlocked yes)
			(layer "F.Fab")
			(hide yes)
			(effects
				(font
					(size 1.27 1.016)
					(thickness 0.1524)
				)
			)
		)
		(property "Device Type" "SKT-MINI67P-41-GP_SOCKET-G4-SKA"
			(at 12.319 -2.8575 90)
			(unlocked yes)
			(layer "F.Fab")
			(hide yes)
			(effects
				(font
					(size 1.27 1.016)
					(thickness 0.1524)
				)
			)
		)
		(duplicate_pad_numbers_are_jumpers no)
		(pad "" np_thru_hole circle
			(at -9.99998 0 90)
			(size 0.254 0.254)
			(drill 1.1176)
			(layers "*.Cu" "*.Mask")
			(clearance 0.7874)
			(thermal_gap 0.7874)
		)
		(pad "" np_thru_hole circle
			(at 9.99998 0 90)
			(size 0.254 0.254)
			(drill 1.6002)
			(layers "*.Cu" "*.Mask")
			(clearance 1.0287)
			(thermal_gap 1.0287)
		)
		(pad "1" smd rect
			(at -9.249918 -5.275072 90)
			(size 0.3048 1.5494)
			(layers "F.Cu" "F.Mask" "F.Paste")
			(net "GND")
		)
		(pad "2" smd rect
			(at -8.999982 2.275078 90)
			(size 0.3048 1.5494)
			(layers "F.Cu" "F.Mask" "F.Paste")
			(net "P3V3")
		)
		(pad "3" smd rect
			(at -8.750046 -5.275072 90)
			(size 0.3048 1.5494)
			(layers "F.Cu" "F.Mask" "F.Paste")
			(net "GND")
		)
		(pad "4" smd rect
			(at -8.50011 2.275078 90)
			(size 0.3048 1.5494)
			(layers "F.Cu" "F.Mask" "F.Paste")
			(net "P3V3")
		)
		(pad "5" smd rect
			(at -8.24992 -5.275072 90)
			(size 0.3048 1.5494)
			(layers "F.Cu" "F.Mask" "F.Paste")
			(net "P3E_PCH_M2_RX_DN<3>")
		)
		(pad "6" smd rect
			(at -7.999984 2.275078 90)
			(size 0.3048 1.5494)
			(layers "F.Cu" "F.Mask" "F.Paste")
			(net "NC_M2<0>")
		)
		(pad "7" smd rect
			(at -7.750048 -5.275072 90)
			(size 0.3048 1.5494)
			(layers "F.Cu" "F.Mask" "F.Paste")
			(net "P3E_PCH_M2_RX_DP<3>")
		)
		(pad "8" smd rect
			(at -7.500112 2.275078 90)
			(size 0.3048 1.5494)
			(layers "F.Cu" "F.Mask" "F.Paste")
			(net "NC_M2<1>")
		)
		(pad "9" smd rect
			(at -7.249922 -5.275072 90)
			(size 0.3048 1.5494)
			(layers "F.Cu" "F.Mask" "F.Paste")
			(net "GND")
		)
		(pad "10" smd rect
			(at -6.999986 2.275078 90)
			(size 0.3048 1.5494)
			(layers "F.Cu" "F.Mask" "F.Paste")
			(net "TP_LED_M2_ACT_N")
		)
		(pad "11" smd rect
			(at -6.75005 -5.275072 90)
			(size 0.3048 1.5494)
			(layers "F.Cu" "F.Mask" "F.Paste")
			(net "P3E_PCH_M2_TX_C_DN<3>")
		)
		(pad "12" smd rect
			(at -6.500114 2.275078 90)
			(size 0.3048 1.5494)
			(layers "F.Cu" "F.Mask" "F.Paste")
			(net "P3V3")
		)
		(pad "13" smd rect
			(at -6.249924 -5.275072 90)
			(size 0.3048 1.5494)
			(layers "F.Cu" "F.Mask" "F.Paste")
			(net "P3E_PCH_M2_TX_C_DP<3>")
		)
		(pad "14" smd rect
			(at -5.999988 2.275078 90)
			(size 0.3048 1.5494)
			(layers "F.Cu" "F.Mask" "F.Paste")
			(net "P3V3")
		)
		(pad "15" smd rect
			(at -5.750052 -5.275072 90)
			(size 0.3048 1.5494)
			(layers "F.Cu" "F.Mask" "F.Paste")
			(net "GND")
		)
		(pad "16" smd rect
			(at -5.500116 2.275078 90)
			(size 0.3048 1.5494)
			(layers "F.Cu" "F.Mask" "F.Paste")
			(net "P3V3")
		)
		(pad "17" smd rect
			(at -5.249926 -5.275072 90)
			(size 0.3048 1.5494)
			(layers "F.Cu" "F.Mask" "F.Paste")
			(net "P3E_PCH_M2_RX_DN<2>")
		)
		(pad "18" smd rect
			(at -4.99999 2.275078 90)
			(size 0.3048 1.5494)
			(layers "F.Cu" "F.Mask" "F.Paste")
			(net "P3V3")
		)
		(pad "19" smd rect
			(at -4.750054 -5.275072 90)
			(size 0.3048 1.5494)
			(layers "F.Cu" "F.Mask" "F.Paste")
			(net "P3E_PCH_M2_RX_DP<2>")
		)
		(pad "20" smd rect
			(at -4.500118 2.275078 90)
			(size 0.3048 1.5494)
			(layers "F.Cu" "F.Mask" "F.Paste")
			(net "Net_317")
		)
		(pad "21" smd rect
			(at -4.249928 -5.275072 90)
			(size 0.3048 1.5494)
			(layers "F.Cu" "F.Mask" "F.Paste")
			(net "GND")
		)
		(pad "22" smd rect
			(at -3.999992 2.275078 90)
			(size 0.3048 1.5494)
			(layers "F.Cu" "F.Mask" "F.Paste")
			(net "Net_318")
		)
		(pad "23" smd rect
			(at -3.750056 -5.275072 90)
			(size 0.3048 1.5494)
			(layers "F.Cu" "F.Mask" "F.Paste")
			(net "P3E_PCH_M2_TX_C_DN<2>")
		)
		(pad "24" smd rect
			(at -3.50012 2.275078 90)
			(size 0.3048 1.5494)
			(layers "F.Cu" "F.Mask" "F.Paste")
			(net "Net_319")
		)
		(pad "25" smd rect
			(at -3.24993 -5.275072 90)
			(size 0.3048 1.5494)
			(layers "F.Cu" "F.Mask" "F.Paste")
			(net "P3E_PCH_M2_TX_C_DP<2>")
		)
		(pad "26" smd rect
			(at -2.999994 2.275078 90)
			(size 0.3048 1.5494)
			(layers "F.Cu" "F.Mask" "F.Paste")
			(net "Net_320")
		)
		(pad "27" smd rect
			(at -2.750058 -5.275072 90)
			(size 0.3048 1.5494)
			(layers "F.Cu" "F.Mask" "F.Paste")
			(net "GND")
		)
		(pad "28" smd rect
			(at -2.500122 2.275078 90)
			(size 0.3048 1.5494)
			(layers "F.Cu" "F.Mask" "F.Paste")
			(net "Net_321")
		)
		(pad "29" smd rect
			(at -2.249932 -5.275072 90)
			(size 0.3048 1.5494)
			(layers "F.Cu" "F.Mask" "F.Paste")
			(net "P3E_PCH_M2_RX_DN<1>")
		)
		(pad "30" smd rect
			(at -1.999996 2.275078 90)
			(size 0.3048 1.5494)
			(layers "F.Cu" "F.Mask" "F.Paste")
			(net "Net_322")
		)
		(pad "31" smd rect
			(at -1.75006 -5.275072 90)
			(size 0.3048 1.5494)
			(layers "F.Cu" "F.Mask" "F.Paste")
			(net "P3E_PCH_M2_RX_DP<1>")
		)
		(pad "32" smd rect
			(at -1.500124 2.275078 90)
			(size 0.3048 1.5494)
			(layers "F.Cu" "F.Mask" "F.Paste")
			(net "Net_323")
		)
		(pad "33" smd rect
			(at -1.249934 -5.275072 90)
			(size 0.3048 1.5494)
			(layers "F.Cu" "F.Mask" "F.Paste")
			(net "GND")
		)
		(pad "34" smd rect
			(at -0.999998 2.275078 90)
			(size 0.3048 1.5494)
			(layers "F.Cu" "F.Mask" "F.Paste")
			(net "Net_324")
		)
		(pad "35" smd rect
			(at -0.750062 -5.275072 90)
			(size 0.3048 1.5494)
			(layers "F.Cu" "F.Mask" "F.Paste")
			(net "P3E_PCH_M2_TX_C_DN<1>")
		)
		(pad "36" smd rect
			(at -0.500126 2.275078 90)
			(size 0.3048 1.5494)
			(layers "F.Cu" "F.Mask" "F.Paste")
			(net "Net_325")
		)
		(pad "37" smd rect
			(at -0.249936 -5.275072 90)
			(size 0.3048 1.5494)
			(layers "F.Cu" "F.Mask" "F.Paste")
			(net "P3E_PCH_M2_TX_C_DP<1>")
		)
		(pad "38" smd rect
			(at 0 2.275078 90)
			(size 0.3048 1.5494)
			(layers "F.Cu" "F.Mask" "F.Paste")
			(net "TP_M2_DEVSLP")
		)
		(pad "39" smd rect
			(at 0.249936 -5.275072 90)
			(size 0.3048 1.5494)
			(layers "F.Cu" "F.Mask" "F.Paste")
			(net "GND")
		)
		(pad "40" smd rect
			(at 0.500126 2.275078 90)
			(size 0.3048 1.5494)
			(layers "F.Cu" "F.Mask" "F.Paste")
			(net "SMB_M2_SCL")
		)
		(pad "41" smd rect
			(at 0.750062 -5.275072 90)
			(size 0.3048 1.5494)
			(layers "F.Cu" "F.Mask" "F.Paste")
			(net "P3E_PCH_M2_SATA6G_RX_R_DP")
		)
		(pad "42" smd rect
			(at 0.999998 2.275078 90)
			(size 0.3048 1.5494)
			(layers "F.Cu" "F.Mask" "F.Paste")
			(net "SMB_M2_SDA")
		)
		(pad "43" smd rect
			(at 1.249934 -5.275072 90)
			(size 0.3048 1.5494)
			(layers "F.Cu" "F.Mask" "F.Paste")
			(net "P3E_PCH_M2_SATA6G_RX_R_DN")
		)
		(pad "44" smd rect
			(at 1.500124 2.275078 90)
			(size 0.3048 1.5494)
			(layers "F.Cu" "F.Mask" "F.Paste")
			(net "SMB_M2_ALT_N")
		)
	)
)
